(kicad_pcb
	(version 20260206)
	(generator "pcbnew")
	(generator_version "10.0")
	(general
		(thickness 1.6)
		(legacy_teardrops no)
	)
	(paper "A4")
	(title_block
		(title "04192023_DAF0TMB3IC0_F0TG_MB_C_brd_V02_OCP.brd")
		(comment 1 "Grand Teton / footprints 2500-2508 of 8354")
	)
	(layers
		(0 "F.Cu" signal "TOP")
		(4 "In1.Cu" signal "GND")
		(6 "In2.Cu" signal "IN1")
		(8 "In3.Cu" signal "GND1")
		(10 "In4.Cu" signal "IN2")
		(12 "In5.Cu" signal "GND2")
		(14 "In6.Cu" signal "IN3")
		(16 "In7.Cu" signal "GND3")
		(18 "In8.Cu" signal "VCC")
		(20 "In9.Cu" signal "VCC1")
		(22 "In10.Cu" signal "GND4")
		(24 "In11.Cu" signal "IN4")
		(26 "In12.Cu" signal "GND5")
		(28 "In13.Cu" signal "IN5")
		(30 "In14.Cu" signal "GND6")
		(32 "In15.Cu" signal "IN6")
		(34 "In16.Cu" signal "GND7")
		(2 "B.Cu" signal "BOTTOM")
		(9 "F.Adhes" user "F.Adhesive")
		(11 "B.Adhes" user "B.Adhesive")
		(13 "F.Paste" user "Package Geometry/Pastemask Top")
		(15 "B.Paste" user "Package Geometry/Pastemask Bottom")
		(5 "F.SilkS" user "Ref Des/Silkscreen Top")
		(7 "B.SilkS" user "Ref Des/Silkscreen Bottom")
		(1 "F.Mask" user "Board Geometry/Soldermask Top")
		(3 "B.Mask" user "Board Geometry/Soldermask Bottom")
		(17 "Dwgs.User" user "User.Drawings")
		(19 "Cmts.User" user "User.Comments")
		(21 "Eco1.User" user "User.Eco1")
		(23 "Eco2.User" user "User.Eco2")
		(25 "Edge.Cuts" user "Board Geometry/Outline")
		(27 "Margin" user)
		(31 "F.CrtYd" user "Package Geometry/Place Bound Top")
		(29 "B.CrtYd" user "Package Geometry/Place Bound Bottom")
		(35 "F.Fab" user "Ref Des/Assembly Top")
		(33 "B.Fab" user "Ref Des/Assembly Bottom")
	)
	(footprint ""
		(layer "F.Cu")
		(at 279.708864 -414.051242)
		(property "Reference" "R6864"
			(at 0 0 0)
			(layer "F.SilkS")
			(hide yes)
			(effects
				(font
					(size 1.27 1.27)
				)
			)
		)
		(property "Value" ""
			(at 0 0 0)
			(layer "F.Fab")
			(effects
				(font
					(size 1.27 1.27)
				)
			)
		)
		(duplicate_pad_numbers_are_jumpers no)
		(fp_line
			(start -0.7874 -0.4064)
			(end 0.7874 -0.4064)
			(stroke
				(width 0.1524)
				(type default)
			)
			(layer "F.SilkS")
		)
		(fp_line
			(start -0.7874 0.4064)
			(end -0.7874 -0.4064)
			(stroke
				(width 0.1524)
				(type default)
			)
			(layer "F.SilkS")
		)
		(fp_line
			(start 0.7874 -0.4064)
			(end 0.7874 0.4064)
			(stroke
				(width 0.1524)
				(type default)
			)
			(layer "F.SilkS")
		)
		(fp_line
			(start 0.7874 0.4064)
			(end -0.7874 0.4064)
			(stroke
				(width 0.1524)
				(type default)
			)
			(layer "F.SilkS")
		)
		(fp_line
			(start -0.67945 -0.305054)
			(end -0.12065 -0.305054)
			(stroke
				(width 0.1)
				(type default)
			)
			(layer "F.Fab")
		)
		(fp_line
			(start -0.67945 0.3048)
			(end -0.67945 -0.305054)
			(stroke
				(width 0.1)
				(type default)
			)
			(layer "F.Fab")
		)
		(fp_line
			(start -0.12065 -0.305054)
			(end -0.12065 -0.2794)
			(stroke
				(width 0.1)
				(type default)
			)
			(layer "F.Fab")
		)
		(fp_line
			(start -0.12065 -0.2794)
			(end 0.12065 -0.2794)
			(stroke
				(width 0.1)
				(type default)
			)
			(layer "F.Fab")
		)
		(fp_line
			(start -0.12065 0.2794)
			(end -0.12065 0.3048)
			(stroke
				(width 0.1)
				(type default)
			)
			(layer "F.Fab")
		)
		(fp_line
			(start -0.12065 0.3048)
			(end -0.67945 0.3048)
			(stroke
				(width 0.1)
				(type default)
			)
			(layer "F.Fab")
		)
		(fp_line
			(start 0.120396 0.2794)
			(end -0.12065 0.2794)
			(stroke
				(width 0.1)
				(type default)
			)
			(layer "F.Fab")
		)
		(fp_line
			(start 0.120396 0.3048)
			(end 0.120396 0.2794)
			(stroke
				(width 0.1)
				(type default)
			)
			(layer "F.Fab")
		)
		(fp_line
			(start 0.12065 -0.3048)
			(end 0.67945 -0.3048)
			(stroke
				(width 0.1)
				(type default)
			)
			(layer "F.Fab")
		)
		(fp_line
			(start 0.12065 -0.2794)
			(end 0.12065 -0.3048)
			(stroke
				(width 0.1)
				(type default)
			)
			(layer "F.Fab")
		)
		(fp_line
			(start 0.67945 -0.3048)
			(end 0.67945 0.3048)
			(stroke
				(width 0.1)
				(type default)
			)
			(layer "F.Fab")
		)
		(fp_line
			(start 0.67945 0.3048)
			(end 0.120396 0.3048)
			(stroke
				(width 0.1)
				(type default)
			)
			(layer "F.Fab")
		)
		(pad "1" smd circle
			(at -0.40005 0)
			(size 0 0)
			(layers "F.Cu" "F.Mask" "F.Paste")
			(net "SMB_HOST_CLK_3V3AUX_SCL_R1")
		)
		(pad "2" smd circle
			(at 0.40005 0)
			(size 0 0)
			(layers "F.Cu" "F.Mask" "F.Paste")
			(net "SMB_9ZXL045_P0_SCL")
		)
	)
	(footprint ""
		(layer "F.Cu")
		(at 126.804928 -48.137064)
		(property "Reference" "R6202"
			(at 0 0 0)
			(layer "F.SilkS")
			(hide yes)
			(effects
				(font
					(size 1.27 1.27)
				)
			)
		)
		(property "Value" ""
			(at 0 0 0)
			(layer "F.Fab")
			(effects
				(font
					(size 1.27 1.27)
				)
			)
		)
		(duplicate_pad_numbers_are_jumpers no)
		(fp_line
			(start -0.7874 -0.4064)
			(end 0.7874 -0.4064)
			(stroke
				(width 0.1524)
				(type default)
			)
			(layer "F.SilkS")
		)
		(fp_line
			(start -0.7874 0.4064)
			(end -0.7874 -0.4064)
			(stroke
				(width 0.1524)
				(type default)
			)
			(layer "F.SilkS")
		)
		(fp_line
			(start 0.7874 -0.4064)
			(end 0.7874 0.4064)
			(stroke
				(width 0.1524)
				(type default)
			)
			(layer "F.SilkS")
		)
		(fp_line
			(start 0.7874 0.4064)
			(end -0.7874 0.4064)
			(stroke
				(width 0.1524)
				(type default)
			)
			(layer "F.SilkS")
		)
		(fp_line
			(start -0.67945 -0.305054)
			(end -0.12065 -0.305054)
			(stroke
				(width 0.1)
				(type default)
			)
			(layer "F.Fab")
		)
		(fp_line
			(start -0.67945 0.3048)
			(end -0.67945 -0.305054)
			(stroke
				(width 0.1)
				(type default)
			)
			(layer "F.Fab")
		)
		(fp_line
			(start -0.12065 -0.305054)
			(end -0.12065 -0.2794)
			(stroke
				(width 0.1)
				(type default)
			)
			(layer "F.Fab")
		)
		(fp_line
			(start -0.12065 -0.2794)
			(end 0.12065 -0.2794)
			(stroke
				(width 0.1)
				(type default)
			)
			(layer "F.Fab")
		)
		(fp_line
			(start -0.12065 0.2794)
			(end -0.12065 0.3048)
			(stroke
				(width 0.1)
				(type default)
			)
			(layer "F.Fab")
		)
		(fp_line
			(start -0.12065 0.3048)
			(end -0.67945 0.3048)
			(stroke
				(width 0.1)
				(type default)
			)
			(layer "F.Fab")
		)
		(fp_line
			(start 0.120396 0.2794)
			(end -0.12065 0.2794)
			(stroke
				(width 0.1)
				(type default)
			)
			(layer "F.Fab")
		)
		(fp_line
			(start 0.120396 0.3048)
			(end 0.120396 0.2794)
			(stroke
				(width 0.1)
				(type default)
			)
			(layer "F.Fab")
		)
		(fp_line
			(start 0.12065 -0.3048)
			(end 0.67945 -0.3048)
			(stroke
				(width 0.1)
				(type default)
			)
			(layer "F.Fab")
		)
		(fp_line
			(start 0.12065 -0.2794)
			(end 0.12065 -0.3048)
			(stroke
				(width 0.1)
				(type default)
			)
			(layer "F.Fab")
		)
		(fp_line
			(start 0.67945 -0.3048)
			(end 0.67945 0.3048)
			(stroke
				(width 0.1)
				(type default)
			)
			(layer "F.Fab")
		)
		(fp_line
			(start 0.67945 0.3048)
			(end 0.120396 0.3048)
			(stroke
				(width 0.1)
				(type default)
			)
			(layer "F.Fab")
		)
		(pad "1" smd circle
			(at -0.40005 0)
			(size 0 0)
			(layers "F.Cu" "F.Mask" "F.Paste")
			(net "GND")
		)
		(pad "2" smd circle
			(at 0.40005 0)
			(size 0 0)
			(layers "F.Cu" "F.Mask" "F.Paste")
			(net "USB_CPU0_HUB1_RREF_SS")
		)
	)
	(footprint ""
		(layer "F.Cu")
		(at 313.518296 -381.41783 -90)
		(property "Reference" "C916"
			(at 0 0 270)
			(layer "F.SilkS")
			(hide yes)
			(effects
				(font
					(size 1.27 1.27)
				)
			)
		)
		(property "Value" ""
			(at 0 0 270)
			(layer "F.Fab")
			(effects
				(font
					(size 1.27 1.27)
				)
			)
		)
		(duplicate_pad_numbers_are_jumpers no)
		(fp_line
			(start -0.299974 0.150114)
			(end -0.299974 -0.150114)
			(stroke
				(width 0.1)
				(type default)
			)
			(layer "F.Fab")
		)
		(fp_line
			(start 0.299974 0.150114)
			(end -0.299974 0.150114)
			(stroke
				(width 0.1)
				(type default)
			)
			(layer "F.Fab")
		)
		(fp_line
			(start -0.299974 -0.150114)
			(end 0.299974 -0.150114)
			(stroke
				(width 0.1)
				(type default)
			)
			(layer "F.Fab")
		)
		(fp_line
			(start 0.299974 -0.150114)
			(end 0.299974 0.150114)
			(stroke
				(width 0.1)
				(type default)
			)
			(layer "F.Fab")
		)
		(pad "1" smd rect
			(at -0.2667 0 270)
			(size 0.3048 0.381)
			(layers "F.Cu" "F.Mask" "F.Paste")
			(net "P5E_CPU0_P0_TX_C_DN<8>")
		)
		(pad "2" smd rect
			(at 0.2667 0 270)
			(size 0.3048 0.381)
			(layers "F.Cu" "F.Mask" "F.Paste")
			(net "P5E_CPU0_P0_TX_DN<8>")
		)
	)
	(footprint ""
		(layer "F.Cu")
		(at 361.317032 -261.747762 -90)
		(property "Reference" "C2635"
			(at 0 0 270)
			(layer "F.SilkS")
			(hide yes)
			(effects
				(font
					(size 1.27 1.27)
				)
			)
		)
		(property "Value" ""
			(at 0 0 270)
			(layer "F.Fab")
			(effects
				(font
					(size 1.27 1.27)
				)
			)
		)
		(duplicate_pad_numbers_are_jumpers no)
		(fp_line
			(start -0.7874 0.4064)
			(end -0.7874 -0.4064)
			(stroke
				(width 0.1524)
				(type default)
			)
			(layer "F.SilkS")
		)
		(fp_line
			(start 0.7874 0.4064)
			(end -0.7874 0.4064)
			(stroke
				(width 0.1524)
				(type default)
			)
			(layer "F.SilkS")
		)
		(fp_line
			(start -0.7874 -0.4064)
			(end 0.7874 -0.4064)
			(stroke
				(width 0.1524)
				(type default)
			)
			(layer "F.SilkS")
		)
		(fp_line
			(start 0.7874 -0.4064)
			(end 0.7874 0.4064)
			(stroke
				(width 0.1524)
				(type default)
			)
			(layer "F.SilkS")
		)
		(fp_line
			(start -0.67945 0.3048)
			(end -0.67945 -0.305054)
			(stroke
				(width 0.1)
				(type default)
			)
			(layer "F.Fab")
		)
		(fp_line
			(start -0.12065 0.3048)
			(end -0.67945 0.3048)
			(stroke
				(width 0.1)
				(type default)
			)
			(layer "F.Fab")
		)
		(fp_line
			(start 0.120396 0.3048)
			(end 0.120396 0.2794)
			(stroke
				(width 0.1)
				(type default)
			)
			(layer "F.Fab")
		)
		(fp_line
			(start 0.67945 0.3048)
			(end 0.120396 0.3048)
			(stroke
				(width 0.1)
				(type default)
			)
			(layer "F.Fab")
		)
		(fp_line
			(start -0.12065 0.2794)
			(end -0.12065 0.3048)
			(stroke
				(width 0.1)
				(type default)
			)
			(layer "F.Fab")
		)
		(fp_line
			(start 0.120396 0.2794)
			(end -0.12065 0.2794)
			(stroke
				(width 0.1)
				(type default)
			)
			(layer "F.Fab")
		)
		(fp_line
			(start -0.12065 -0.2794)
			(end 0.12065 -0.2794)
			(stroke
				(width 0.1)
				(type default)
			)
			(layer "F.Fab")
		)
		(fp_line
			(start 0.12065 -0.2794)
			(end 0.12065 -0.3048)
			(stroke
				(width 0.1)
				(type default)
			)
			(layer "F.Fab")
		)
		(fp_line
			(start 0.12065 -0.3048)
			(end 0.67945 -0.3048)
			(stroke
				(width 0.1)
				(type default)
			)
			(layer "F.Fab")
		)
		(fp_line
			(start 0.67945 -0.3048)
			(end 0.67945 0.3048)
			(stroke
				(width 0.1)
				(type default)
			)
			(layer "F.Fab")
		)
		(fp_line
			(start -0.67945 -0.305054)
			(end -0.12065 -0.305054)
			(stroke
				(width 0.1)
				(type default)
			)
			(layer "F.Fab")
		)
		(fp_line
			(start -0.12065 -0.305054)
			(end -0.12065 -0.2794)
			(stroke
				(width 0.1)
				(type default)
			)
			(layer "F.Fab")
		)
		(pad "1" smd circle
			(at -0.40005 0 270)
			(size 0 0)
			(layers "F.Cu" "F.Mask" "F.Paste")
			(net "PVDD11_S3_P0")
		)
		(pad "2" smd circle
			(at 0.40005 0 270)
			(size 0 0)
			(layers "F.Cu" "F.Mask" "F.Paste")
			(net "GND")
		)
	)
	(footprint ""
		(layer "F.Cu")
		(at 138.2014 -389.27786 90)
		(property "Reference" "R1435"
			(at 0 0 90)
			(layer "F.SilkS")
			(hide yes)
			(effects
				(font
					(size 1.27 1.27)
				)
			)
		)
		(property "Value" ""
			(at 0 0 90)
			(layer "F.Fab")
			(effects
				(font
					(size 1.27 1.27)
				)
			)
		)
		(duplicate_pad_numbers_are_jumpers no)
		(fp_line
			(start 0.32512 -0.175006)
			(end 0.32512 0.175006)
			(stroke
				(width 0.1)
				(type default)
			)
			(layer "F.Fab")
		)
		(fp_line
			(start -0.32512 -0.175006)
			(end 0.32512 -0.175006)
			(stroke
				(width 0.1)
				(type default)
			)
			(layer "F.Fab")
		)
		(fp_line
			(start 0.32512 0.175006)
			(end -0.32512 0.175006)
			(stroke
				(width 0.1)
				(type default)
			)
			(layer "F.Fab")
		)
		(fp_line
			(start -0.32512 0.175006)
			(end -0.32512 -0.175006)
			(stroke
				(width 0.1)
				(type default)
			)
			(layer "F.Fab")
		)
		(pad "1" smd rect
			(at -0.2667 0 90)
			(size 0.3048 0.381)
			(layers "F.Cu" "F.Mask" "F.Paste")
			(net "RXDET_BYP_RT_CPU1_P3")
		)
		(pad "2" smd rect
			(at 0.2667 0 270)
			(size 0.3048 0.381)
			(layers "F.Cu" "F.Mask" "F.Paste")
			(net "GND")
		)
	)
	(footprint ""
		(layer "F.Cu")
		(at 358.959404 -28.695396)
		(property "Reference" "Q61"
			(at -0.26924 -2.352548 0)
			(unlocked yes)
			(layer "F.SilkS")
			(effects
				(font
					(size 0.7874 0.5842)
					(thickness 0.1524)
				)
			)
		)
		(property "Value" ""
			(at 0 0 0)
			(layer "F.Fab")
			(effects
				(font
					(size 1.27 1.27)
				)
			)
		)
		(duplicate_pad_numbers_are_jumpers no)
		(fp_line
			(start -1.8796 -1.651)
			(end 1.8796 -1.651)
			(stroke
				(width 0.1524)
				(type default)
			)
			(layer "F.SilkS")
		)
		(fp_line
			(start -1.8796 1.651)
			(end -1.8796 -1.651)
			(stroke
				(width 0.1524)
				(type default)
			)
			(layer "F.SilkS")
		)
		(fp_line
			(start 1.8796 -1.651)
			(end 1.8796 1.651)
			(stroke
				(width 0.1524)
				(type default)
			)
			(layer "F.SilkS")
		)
		(fp_line
			(start 1.8796 1.651)
			(end -1.8796 1.651)
			(stroke
				(width 0.1524)
				(type default)
			)
			(layer "F.SilkS")
		)
		(fp_line
			(start -0.700024 -1.500124)
			(end 0.700024 -1.500124)
			(stroke
				(width 0.1)
				(type default)
			)
			(layer "F.Fab")
		)
		(fp_line
			(start -0.700024 1.500124)
			(end -0.700024 -1.500124)
			(stroke
				(width 0.1)
				(type default)
			)
			(layer "F.Fab")
		)
		(fp_line
			(start 0.700024 -1.500124)
			(end 0.700024 1.500124)
			(stroke
				(width 0.1)
				(type default)
			)
			(layer "F.Fab")
		)
		(fp_line
			(start 0.700024 1.500124)
			(end -0.700024 1.500124)
			(stroke
				(width 0.1)
				(type default)
			)
			(layer "F.Fab")
		)
		(pad "D" smd rect
			(at 1.119886 0 270)
			(size 1.016 1.2192)
			(layers "F.Cu" "F.Mask" "F.Paste")
			(net "UART_LS_EN_R_N")
		)
		(pad "G" smd rect
			(at -1.119886 -0.999998 270)
			(size 1.016 1.2192)
			(layers "F.Cu" "F.Mask" "F.Paste")
			(net "UART_LS_EN")
		)
		(pad "S" smd rect
			(at -1.119886 0.999998 270)
			(size 1.016 1.2192)
			(layers "F.Cu" "F.Mask" "F.Paste")
			(net "GND")
		)
	)
	(footprint ""
		(layer "F.Cu")
		(at 136.840976 -376.067828)
		(property "Reference" "C50"
			(at 0 0 0)
			(layer "F.SilkS")
			(hide yes)
			(effects
				(font
					(size 1.27 1.27)
				)
			)
		)
		(property "Value" ""
			(at 0 0 0)
			(layer "F.Fab")
			(effects
				(font
					(size 1.27 1.27)
				)
			)
		)
		(duplicate_pad_numbers_are_jumpers no)
		(fp_line
			(start -0.299974 -0.150114)
			(end 0.299974 -0.150114)
			(stroke
				(width 0.1)
				(type default)
			)
			(layer "F.Fab")
		)
		(fp_line
			(start -0.299974 0.150114)
			(end -0.299974 -0.150114)
			(stroke
				(width 0.1)
				(type default)
			)
			(layer "F.Fab")
		)
		(fp_line
			(start 0.299974 -0.150114)
			(end 0.299974 0.150114)
			(stroke
				(width 0.1)
				(type default)
			)
			(layer "F.Fab")
		)
		(fp_line
			(start 0.299974 0.150114)
			(end -0.299974 0.150114)
			(stroke
				(width 0.1)
				(type default)
			)
			(layer "F.Fab")
		)
		(pad "1" smd rect
			(at -0.2667 0)
			(size 0.3048 0.381)
			(layers "F.Cu" "F.Mask" "F.Paste")
			(net "P5E_CPU1_P3_TX_C_DN<14>")
		)
		(pad "2" smd rect
			(at 0.2667 0)
			(size 0.3048 0.381)
			(layers "F.Cu" "F.Mask" "F.Paste")
			(net "P5E_CPU1_P3_TX_DN<14>")
		)
	)
	(footprint ""
		(layer "F.Cu")
		(at 271.728184 -343.712038 180)
		(property "Reference" "PC163"
			(at 0 0 180)
			(layer "F.SilkS")
			(hide yes)
			(effects
				(font
					(size 1.27 1.27)
				)
			)
		)
		(property "Value" ""
			(at 0 0 180)
			(layer "F.Fab")
			(effects
				(font
					(size 1.27 1.27)
				)
			)
		)
		(duplicate_pad_numbers_are_jumpers no)
		(fp_line
			(start 0.7874 0.4064)
			(end -0.7874 0.4064)
			(stroke
				(width 0.1524)
				(type default)
			)
			(layer "F.SilkS")
		)
		(fp_line
			(start 0.7874 -0.4064)
			(end 0.7874 0.4064)
			(stroke
				(width 0.1524)
				(type default)
			)
			(layer "F.SilkS")
		)
		(fp_line
			(start -0.7874 0.4064)
			(end -0.7874 -0.4064)
			(stroke
				(width 0.1524)
				(type default)
			)
			(layer "F.SilkS")
		)
		(fp_line
			(start -0.7874 -0.4064)
			(end 0.7874 -0.4064)
			(stroke
				(width 0.1524)
				(type default)
			)
			(layer "F.SilkS")
		)
		(fp_line
			(start 0.67945 0.3048)
			(end 0.120396 0.3048)
			(stroke
				(width 0.1)
				(type default)
			)
			(layer "F.Fab")
		)
		(fp_line
			(start 0.67945 -0.3048)
			(end 0.67945 0.3048)
			(stroke
				(width 0.1)
				(type default)
			)
			(layer "F.Fab")
		)
		(fp_line
			(start 0.12065 -0.2794)
			(end 0.12065 -0.3048)
			(stroke
				(width 0.1)
				(type default)
			)
			(layer "F.Fab")
		)
		(fp_line
			(start 0.12065 -0.3048)
			(end 0.67945 -0.3048)
			(stroke
				(width 0.1)
				(type default)
			)
			(layer "F.Fab")
		)
		(fp_line
			(start 0.120396 0.3048)
			(end 0.120396 0.2794)
			(stroke
				(width 0.1)
				(type default)
			)
			(layer "F.Fab")
		)
		(fp_line
			(start 0.120396 0.2794)
			(end -0.12065 0.2794)
			(stroke
				(width 0.1)
				(type default)
			)
			(layer "F.Fab")
		)
		(fp_line
			(start -0.12065 0.3048)
			(end -0.67945 0.3048)
			(stroke
				(width 0.1)
				(type default)
			)
			(layer "F.Fab")
		)
		(fp_line
			(start -0.12065 0.2794)
			(end -0.12065 0.3048)
			(stroke
				(width 0.1)
				(type default)
			)
			(layer "F.Fab")
		)
		(fp_line
			(start -0.12065 -0.2794)
			(end 0.12065 -0.2794)
			(stroke
				(width 0.1)
				(type default)
			)
			(layer "F.Fab")
		)
		(fp_line
			(start -0.12065 -0.305054)
			(end -0.12065 -0.2794)
			(stroke
				(width 0.1)
				(type default)
			)
			(layer "F.Fab")
		)
		(fp_line
			(start -0.67945 0.3048)
			(end -0.67945 -0.305054)
			(stroke
				(width 0.1)
				(type default)
			)
			(layer "F.Fab")
		)
		(fp_line
			(start -0.67945 -0.305054)
			(end -0.12065 -0.305054)
			(stroke
				(width 0.1)
				(type default)
			)
			(layer "F.Fab")
		)
		(pad "1" smd circle
			(at -0.40005 0 180)
			(size 0 0)
			(layers "F.Cu" "F.Mask" "F.Paste")
			(net "SW_PVDDIO_P0_SW4")
		)
		(pad "2" smd circle
			(at 0.40005 0 180)
			(size 0 0)
			(layers "F.Cu" "F.Mask" "F.Paste")
			(net "SW_PVDDIO_P0_SW4_RC")
		)
	)
	(footprint ""
		(layer "F.Cu")
		(at 312.603896 -381.41783 -90)
		(property "Reference" "C917"
			(at 0 0 270)
			(layer "F.SilkS")
			(hide yes)
			(effects
				(font
					(size 1.27 1.27)
				)
			)
		)
		(property "Value" ""
			(at 0 0 270)
			(layer "F.Fab")
			(effects
				(font
					(size 1.27 1.27)
				)
			)
		)
		(duplicate_pad_numbers_are_jumpers no)
		(fp_line
			(start -0.299974 0.150114)
			(end -0.299974 -0.150114)
			(stroke
				(width 0.1)
				(type default)
			)
			(layer "F.Fab")
		)
		(fp_line
			(start 0.299974 0.150114)
			(end -0.299974 0.150114)
			(stroke
				(width 0.1)
				(type default)
			)
			(layer "F.Fab")
		)
		(fp_line
			(start -0.299974 -0.150114)
			(end 0.299974 -0.150114)
			(stroke
				(width 0.1)
				(type default)
			)
			(layer "F.Fab")
		)
		(fp_line
			(start 0.299974 -0.150114)
			(end 0.299974 0.150114)
			(stroke
				(width 0.1)
				(type default)
			)
			(layer "F.Fab")
		)
		(pad "1" smd rect
			(at -0.2667 0 270)
			(size 0.3048 0.381)
			(layers "F.Cu" "F.Mask" "F.Paste")
			(net "P5E_CPU0_P0_TX_C_DP<8>")
		)
		(pad "2" smd rect
			(at 0.2667 0 270)
			(size 0.3048 0.381)
			(layers "F.Cu" "F.Mask" "F.Paste")
			(net "P5E_CPU0_P0_TX_DP<8>")
		)
	)
)
